(kicad_pcb
	(version 20260206)
	(generator "pcbnew")
	(generator_version "10.0")
	(general
		(thickness 1.6)
		(legacy_teardrops no)
	)
	(paper "A4")
	(title_block
		(title "04192023_DAF0TMB3IC0_F0TG_MB_C_brd_V02_OCP.brd")
		(comment 1 "Grand Teton / footprints 451-456 of 8354")
	)
	(layers
		(0 "F.Cu" signal "TOP")
		(4 "In1.Cu" signal "GND")
		(6 "In2.Cu" signal "IN1")
		(8 "In3.Cu" signal "GND1")
		(10 "In4.Cu" signal "IN2")
		(12 "In5.Cu" signal "GND2")
		(14 "In6.Cu" signal "IN3")
		(16 "In7.Cu" signal "GND3")
		(18 "In8.Cu" signal "VCC")
		(20 "In9.Cu" signal "VCC1")
		(22 "In10.Cu" signal "GND4")
		(24 "In11.Cu" signal "IN4")
		(26 "In12.Cu" signal "GND5")
		(28 "In13.Cu" signal "IN5")
		(30 "In14.Cu" signal "GND6")
		(32 "In15.Cu" signal "IN6")
		(34 "In16.Cu" signal "GND7")
		(2 "B.Cu" signal "BOTTOM")
		(9 "F.Adhes" user "F.Adhesive")
		(11 "B.Adhes" user "B.Adhesive")
		(13 "F.Paste" user "Package Geometry/Pastemask Top")
		(15 "B.Paste" user "Package Geometry/Pastemask Bottom")
		(5 "F.SilkS" user "Ref Des/Silkscreen Top")
		(7 "B.SilkS" user "Ref Des/Silkscreen Bottom")
		(1 "F.Mask" user "Board Geometry/Soldermask Top")
		(3 "B.Mask" user "Board Geometry/Soldermask Bottom")
		(17 "Dwgs.User" user "User.Drawings")
		(19 "Cmts.User" user "User.Comments")
		(21 "Eco1.User" user "User.Eco1")
		(23 "Eco2.User" user "User.Eco2")
		(25 "Edge.Cuts" user "Board Geometry/Outline")
		(27 "Margin" user)
		(31 "F.CrtYd" user "Package Geometry/Place Bound Top")
		(29 "B.CrtYd" user "Package Geometry/Place Bound Bottom")
		(35 "F.Fab" user "Ref Des/Assembly Top")
		(33 "B.Fab" user "Ref Des/Assembly Bottom")
	)
	(footprint ""
		(layer "F.Cu")
		(at 420.06266 -109.231176 -90)
		(property "Reference" "R3845"
			(at 0 0 270)
			(layer "F.SilkS")
			(hide yes)
			(effects
				(font
					(size 1.27 1.27)
				)
			)
		)
		(property "Value" ""
			(at 0 0 270)
			(layer "F.Fab")
			(effects
				(font
					(size 1.27 1.27)
				)
			)
		)
		(duplicate_pad_numbers_are_jumpers no)
		(fp_line
			(start -0.7874 0.4064)
			(end -0.7874 -0.4064)
			(stroke
				(width 0.1524)
				(type default)
			)
			(layer "F.SilkS")
		)
		(fp_line
			(start 0.7874 0.4064)
			(end -0.7874 0.4064)
			(stroke
				(width 0.1524)
				(type default)
			)
			(layer "F.SilkS")
		)
		(fp_line
			(start -0.7874 -0.4064)
			(end 0.7874 -0.4064)
			(stroke
				(width 0.1524)
				(type default)
			)
			(layer "F.SilkS")
		)
		(fp_line
			(start 0.7874 -0.4064)
			(end 0.7874 0.4064)
			(stroke
				(width 0.1524)
				(type default)
			)
			(layer "F.SilkS")
		)
		(fp_line
			(start -0.67945 0.3048)
			(end -0.67945 -0.305054)
			(stroke
				(width 0.1)
				(type default)
			)
			(layer "F.Fab")
		)
		(fp_line
			(start -0.12065 0.3048)
			(end -0.67945 0.3048)
			(stroke
				(width 0.1)
				(type default)
			)
			(layer "F.Fab")
		)
		(fp_line
			(start 0.120396 0.3048)
			(end 0.120396 0.2794)
			(stroke
				(width 0.1)
				(type default)
			)
			(layer "F.Fab")
		)
		(fp_line
			(start 0.67945 0.3048)
			(end 0.120396 0.3048)
			(stroke
				(width 0.1)
				(type default)
			)
			(layer "F.Fab")
		)
		(fp_line
			(start -0.12065 0.2794)
			(end -0.12065 0.3048)
			(stroke
				(width 0.1)
				(type default)
			)
			(layer "F.Fab")
		)
		(fp_line
			(start 0.120396 0.2794)
			(end -0.12065 0.2794)
			(stroke
				(width 0.1)
				(type default)
			)
			(layer "F.Fab")
		)
		(fp_line
			(start -0.12065 -0.2794)
			(end 0.12065 -0.2794)
			(stroke
				(width 0.1)
				(type default)
			)
			(layer "F.Fab")
		)
		(fp_line
			(start 0.12065 -0.2794)
			(end 0.12065 -0.3048)
			(stroke
				(width 0.1)
				(type default)
			)
			(layer "F.Fab")
		)
		(fp_line
			(start 0.12065 -0.3048)
			(end 0.67945 -0.3048)
			(stroke
				(width 0.1)
				(type default)
			)
			(layer "F.Fab")
		)
		(fp_line
			(start 0.67945 -0.3048)
			(end 0.67945 0.3048)
			(stroke
				(width 0.1)
				(type default)
			)
			(layer "F.Fab")
		)
		(fp_line
			(start -0.67945 -0.305054)
			(end -0.12065 -0.305054)
			(stroke
				(width 0.1)
				(type default)
			)
			(layer "F.Fab")
		)
		(fp_line
			(start -0.12065 -0.305054)
			(end -0.12065 -0.2794)
			(stroke
				(width 0.1)
				(type default)
			)
			(layer "F.Fab")
		)
		(pad "1" smd circle
			(at -0.40005 0 270)
			(size 0 0)
			(layers "F.Cu" "F.Mask" "F.Paste")
			(net "P3V3_OCP_SFF_EN_R")
		)
		(pad "2" smd circle
			(at 0.40005 0 270)
			(size 0 0)
			(layers "F.Cu" "F.Mask" "F.Paste")
			(net "P3V3_OCP_EN_1_R2")
		)
	)
	(footprint ""
		(layer "F.Cu")
		(at 184.310528 -426.40504 -90)
		(property "Reference" "R3517"
			(at 0 0 270)
			(layer "F.SilkS")
			(hide yes)
			(effects
				(font
					(size 1.27 1.27)
				)
			)
		)
		(property "Value" ""
			(at 0 0 270)
			(layer "F.Fab")
			(effects
				(font
					(size 1.27 1.27)
				)
			)
		)
		(duplicate_pad_numbers_are_jumpers no)
		(fp_line
			(start -0.7874 0.4064)
			(end -0.7874 -0.4064)
			(stroke
				(width 0.1524)
				(type default)
			)
			(layer "F.SilkS")
		)
		(fp_line
			(start 0.7874 0.4064)
			(end -0.7874 0.4064)
			(stroke
				(width 0.1524)
				(type default)
			)
			(layer "F.SilkS")
		)
		(fp_line
			(start -0.7874 -0.4064)
			(end 0.7874 -0.4064)
			(stroke
				(width 0.1524)
				(type default)
			)
			(layer "F.SilkS")
		)
		(fp_line
			(start 0.7874 -0.4064)
			(end 0.7874 0.4064)
			(stroke
				(width 0.1524)
				(type default)
			)
			(layer "F.SilkS")
		)
		(fp_line
			(start -0.67945 0.3048)
			(end -0.67945 -0.305054)
			(stroke
				(width 0.1)
				(type default)
			)
			(layer "F.Fab")
		)
		(fp_line
			(start -0.12065 0.3048)
			(end -0.67945 0.3048)
			(stroke
				(width 0.1)
				(type default)
			)
			(layer "F.Fab")
		)
		(fp_line
			(start 0.120396 0.3048)
			(end 0.120396 0.2794)
			(stroke
				(width 0.1)
				(type default)
			)
			(layer "F.Fab")
		)
		(fp_line
			(start 0.67945 0.3048)
			(end 0.120396 0.3048)
			(stroke
				(width 0.1)
				(type default)
			)
			(layer "F.Fab")
		)
		(fp_line
			(start -0.12065 0.2794)
			(end -0.12065 0.3048)
			(stroke
				(width 0.1)
				(type default)
			)
			(layer "F.Fab")
		)
		(fp_line
			(start 0.120396 0.2794)
			(end -0.12065 0.2794)
			(stroke
				(width 0.1)
				(type default)
			)
			(layer "F.Fab")
		)
		(fp_line
			(start -0.12065 -0.2794)
			(end 0.12065 -0.2794)
			(stroke
				(width 0.1)
				(type default)
			)
			(layer "F.Fab")
		)
		(fp_line
			(start 0.12065 -0.2794)
			(end 0.12065 -0.3048)
			(stroke
				(width 0.1)
				(type default)
			)
			(layer "F.Fab")
		)
		(fp_line
			(start 0.12065 -0.3048)
			(end 0.67945 -0.3048)
			(stroke
				(width 0.1)
				(type default)
			)
			(layer "F.Fab")
		)
		(fp_line
			(start 0.67945 -0.3048)
			(end 0.67945 0.3048)
			(stroke
				(width 0.1)
				(type default)
			)
			(layer "F.Fab")
		)
		(fp_line
			(start -0.67945 -0.305054)
			(end -0.12065 -0.305054)
			(stroke
				(width 0.1)
				(type default)
			)
			(layer "F.Fab")
		)
		(fp_line
			(start -0.12065 -0.305054)
			(end -0.12065 -0.2794)
			(stroke
				(width 0.1)
				(type default)
			)
			(layer "F.Fab")
		)
		(pad "1" smd circle
			(at -0.40005 0 270)
			(size 0 0)
			(layers "F.Cu" "F.Mask" "F.Paste")
			(net "GPU_PEX_STRAP1")
		)
		(pad "2" smd circle
			(at 0.40005 0 270)
			(size 0 0)
			(layers "F.Cu" "F.Mask" "F.Paste")
			(net "GPU_PEX_STRAP1_R")
		)
	)
	(footprint ""
		(layer "F.Cu")
		(at 388.074662 -143.323056 -90)
		(property "Reference" "R6076"
			(at 0 0 270)
			(layer "F.SilkS")
			(hide yes)
			(effects
				(font
					(size 1.27 1.27)
				)
			)
		)
		(property "Value" ""
			(at 0 0 270)
			(layer "F.Fab")
			(effects
				(font
					(size 1.27 1.27)
				)
			)
		)
		(duplicate_pad_numbers_are_jumpers no)
		(fp_line
			(start -0.7874 0.4064)
			(end -0.7874 -0.4064)
			(stroke
				(width 0.1524)
				(type default)
			)
			(layer "F.SilkS")
		)
		(fp_line
			(start 0.7874 0.4064)
			(end -0.7874 0.4064)
			(stroke
				(width 0.1524)
				(type default)
			)
			(layer "F.SilkS")
		)
		(fp_line
			(start -0.7874 -0.4064)
			(end 0.7874 -0.4064)
			(stroke
				(width 0.1524)
				(type default)
			)
			(layer "F.SilkS")
		)
		(fp_line
			(start 0.7874 -0.4064)
			(end 0.7874 0.4064)
			(stroke
				(width 0.1524)
				(type default)
			)
			(layer "F.SilkS")
		)
		(fp_line
			(start -0.67945 0.3048)
			(end -0.67945 -0.305054)
			(stroke
				(width 0.1)
				(type default)
			)
			(layer "F.Fab")
		)
		(fp_line
			(start -0.12065 0.3048)
			(end -0.67945 0.3048)
			(stroke
				(width 0.1)
				(type default)
			)
			(layer "F.Fab")
		)
		(fp_line
			(start 0.120396 0.3048)
			(end 0.120396 0.2794)
			(stroke
				(width 0.1)
				(type default)
			)
			(layer "F.Fab")
		)
		(fp_line
			(start 0.67945 0.3048)
			(end 0.120396 0.3048)
			(stroke
				(width 0.1)
				(type default)
			)
			(layer "F.Fab")
		)
		(fp_line
			(start -0.12065 0.2794)
			(end -0.12065 0.3048)
			(stroke
				(width 0.1)
				(type default)
			)
			(layer "F.Fab")
		)
		(fp_line
			(start 0.120396 0.2794)
			(end -0.12065 0.2794)
			(stroke
				(width 0.1)
				(type default)
			)
			(layer "F.Fab")
		)
		(fp_line
			(start -0.12065 -0.2794)
			(end 0.12065 -0.2794)
			(stroke
				(width 0.1)
				(type default)
			)
			(layer "F.Fab")
		)
		(fp_line
			(start 0.12065 -0.2794)
			(end 0.12065 -0.3048)
			(stroke
				(width 0.1)
				(type default)
			)
			(layer "F.Fab")
		)
		(fp_line
			(start 0.12065 -0.3048)
			(end 0.67945 -0.3048)
			(stroke
				(width 0.1)
				(type default)
			)
			(layer "F.Fab")
		)
		(fp_line
			(start 0.67945 -0.3048)
			(end 0.67945 0.3048)
			(stroke
				(width 0.1)
				(type default)
			)
			(layer "F.Fab")
		)
		(fp_line
			(start -0.67945 -0.305054)
			(end -0.12065 -0.305054)
			(stroke
				(width 0.1)
				(type default)
			)
			(layer "F.Fab")
		)
		(fp_line
			(start -0.12065 -0.305054)
			(end -0.12065 -0.2794)
			(stroke
				(width 0.1)
				(type default)
			)
			(layer "F.Fab")
		)
		(pad "1" smd circle
			(at -0.40005 0 270)
			(size 0 0)
			(layers "F.Cu" "F.Mask" "F.Paste")
			(net "SMB_SCM_2_R3_SCL")
		)
		(pad "2" smd circle
			(at 0.40005 0 270)
			(size 0 0)
			(layers "F.Cu" "F.Mask" "F.Paste")
			(net "SMB_SCM_2_R4_SCL")
		)
	)
	(footprint ""
		(layer "F.Cu")
		(at 365.835692 -262.204962 180)
		(property "Reference" "C2133"
			(at 0 0 180)
			(layer "F.SilkS")
			(hide yes)
			(effects
				(font
					(size 1.27 1.27)
				)
			)
		)
		(property "Value" ""
			(at 0 0 180)
			(layer "F.Fab")
			(effects
				(font
					(size 1.27 1.27)
				)
			)
		)
		(duplicate_pad_numbers_are_jumpers no)
		(fp_line
			(start 0.7874 0.4064)
			(end -0.7874 0.4064)
			(stroke
				(width 0.1524)
				(type default)
			)
			(layer "F.SilkS")
		)
		(fp_line
			(start 0.7874 -0.4064)
			(end 0.7874 0.4064)
			(stroke
				(width 0.1524)
				(type default)
			)
			(layer "F.SilkS")
		)
		(fp_line
			(start -0.7874 0.4064)
			(end -0.7874 -0.4064)
			(stroke
				(width 0.1524)
				(type default)
			)
			(layer "F.SilkS")
		)
		(fp_line
			(start -0.7874 -0.4064)
			(end 0.7874 -0.4064)
			(stroke
				(width 0.1524)
				(type default)
			)
			(layer "F.SilkS")
		)
		(fp_line
			(start 0.67945 0.3048)
			(end 0.120396 0.3048)
			(stroke
				(width 0.1)
				(type default)
			)
			(layer "F.Fab")
		)
		(fp_line
			(start 0.67945 -0.3048)
			(end 0.67945 0.3048)
			(stroke
				(width 0.1)
				(type default)
			)
			(layer "F.Fab")
		)
		(fp_line
			(start 0.12065 -0.2794)
			(end 0.12065 -0.3048)
			(stroke
				(width 0.1)
				(type default)
			)
			(layer "F.Fab")
		)
		(fp_line
			(start 0.12065 -0.3048)
			(end 0.67945 -0.3048)
			(stroke
				(width 0.1)
				(type default)
			)
			(layer "F.Fab")
		)
		(fp_line
			(start 0.120396 0.3048)
			(end 0.120396 0.2794)
			(stroke
				(width 0.1)
				(type default)
			)
			(layer "F.Fab")
		)
		(fp_line
			(start 0.120396 0.2794)
			(end -0.12065 0.2794)
			(stroke
				(width 0.1)
				(type default)
			)
			(layer "F.Fab")
		)
		(fp_line
			(start -0.12065 0.3048)
			(end -0.67945 0.3048)
			(stroke
				(width 0.1)
				(type default)
			)
			(layer "F.Fab")
		)
		(fp_line
			(start -0.12065 0.2794)
			(end -0.12065 0.3048)
			(stroke
				(width 0.1)
				(type default)
			)
			(layer "F.Fab")
		)
		(fp_line
			(start -0.12065 -0.2794)
			(end 0.12065 -0.2794)
			(stroke
				(width 0.1)
				(type default)
			)
			(layer "F.Fab")
		)
		(fp_line
			(start -0.12065 -0.305054)
			(end -0.12065 -0.2794)
			(stroke
				(width 0.1)
				(type default)
			)
			(layer "F.Fab")
		)
		(fp_line
			(start -0.67945 0.3048)
			(end -0.67945 -0.305054)
			(stroke
				(width 0.1)
				(type default)
			)
			(layer "F.Fab")
		)
		(fp_line
			(start -0.67945 -0.305054)
			(end -0.12065 -0.305054)
			(stroke
				(width 0.1)
				(type default)
			)
			(layer "F.Fab")
		)
		(pad "1" smd circle
			(at -0.40005 0 180)
			(size 0 0)
			(layers "F.Cu" "F.Mask" "F.Paste")
			(net "PVDD11_S3_P0")
		)
		(pad "2" smd circle
			(at 0.40005 0 180)
			(size 0 0)
			(layers "F.Cu" "F.Mask" "F.Paste")
			(net "GND")
		)
	)
	(footprint ""
		(layer "F.Cu")
		(at 363.645958 -257.744976)
		(property "Reference" "C2564"
			(at 0 0 0)
			(layer "F.SilkS")
			(hide yes)
			(effects
				(font
					(size 1.27 1.27)
				)
			)
		)
		(property "Value" ""
			(at 0 0 0)
			(layer "F.Fab")
			(effects
				(font
					(size 1.27 1.27)
				)
			)
		)
		(duplicate_pad_numbers_are_jumpers no)
		(fp_line
			(start -0.7874 -0.4064)
			(end 0.7874 -0.4064)
			(stroke
				(width 0.1524)
				(type default)
			)
			(layer "F.SilkS")
		)
		(fp_line
			(start -0.7874 0.4064)
			(end -0.7874 -0.4064)
			(stroke
				(width 0.1524)
				(type default)
			)
			(layer "F.SilkS")
		)
		(fp_line
			(start 0.7874 -0.4064)
			(end 0.7874 0.4064)
			(stroke
				(width 0.1524)
				(type default)
			)
			(layer "F.SilkS")
		)
		(fp_line
			(start 0.7874 0.4064)
			(end -0.7874 0.4064)
			(stroke
				(width 0.1524)
				(type default)
			)
			(layer "F.SilkS")
		)
		(fp_line
			(start -0.67945 -0.305054)
			(end -0.12065 -0.305054)
			(stroke
				(width 0.1)
				(type default)
			)
			(layer "F.Fab")
		)
		(fp_line
			(start -0.67945 0.3048)
			(end -0.67945 -0.305054)
			(stroke
				(width 0.1)
				(type default)
			)
			(layer "F.Fab")
		)
		(fp_line
			(start -0.12065 -0.305054)
			(end -0.12065 -0.2794)
			(stroke
				(width 0.1)
				(type default)
			)
			(layer "F.Fab")
		)
		(fp_line
			(start -0.12065 -0.2794)
			(end 0.12065 -0.2794)
			(stroke
				(width 0.1)
				(type default)
			)
			(layer "F.Fab")
		)
		(fp_line
			(start -0.12065 0.2794)
			(end -0.12065 0.3048)
			(stroke
				(width 0.1)
				(type default)
			)
			(layer "F.Fab")
		)
		(fp_line
			(start -0.12065 0.3048)
			(end -0.67945 0.3048)
			(stroke
				(width 0.1)
				(type default)
			)
			(layer "F.Fab")
		)
		(fp_line
			(start 0.120396 0.2794)
			(end -0.12065 0.2794)
			(stroke
				(width 0.1)
				(type default)
			)
			(layer "F.Fab")
		)
		(fp_line
			(start 0.120396 0.3048)
			(end 0.120396 0.2794)
			(stroke
				(width 0.1)
				(type default)
			)
			(layer "F.Fab")
		)
		(fp_line
			(start 0.12065 -0.3048)
			(end 0.67945 -0.3048)
			(stroke
				(width 0.1)
				(type default)
			)
			(layer "F.Fab")
		)
		(fp_line
			(start 0.12065 -0.2794)
			(end 0.12065 -0.3048)
			(stroke
				(width 0.1)
				(type default)
			)
			(layer "F.Fab")
		)
		(fp_line
			(start 0.67945 -0.3048)
			(end 0.67945 0.3048)
			(stroke
				(width 0.1)
				(type default)
			)
			(layer "F.Fab")
		)
		(fp_line
			(start 0.67945 0.3048)
			(end 0.120396 0.3048)
			(stroke
				(width 0.1)
				(type default)
			)
			(layer "F.Fab")
		)
		(pad "1" smd circle
			(at -0.40005 0)
			(size 0 0)
			(layers "F.Cu" "F.Mask" "F.Paste")
			(net "PVDDCR_SOC_P0")
		)
		(pad "2" smd circle
			(at 0.40005 0)
			(size 0 0)
			(layers "F.Cu" "F.Mask" "F.Paste")
			(net "GND")
		)
	)
	(footprint ""
		(layer "F.Cu")
		(at 463.371946 -108.567728 180)
		(property "Reference" "R1150"
			(at 0 0 180)
			(layer "F.SilkS")
			(hide yes)
			(effects
				(font
					(size 1.27 1.27)
				)
			)
		)
		(property "Value" ""
			(at 0 0 180)
			(layer "F.Fab")
			(effects
				(font
					(size 1.27 1.27)
				)
			)
		)
		(duplicate_pad_numbers_are_jumpers no)
		(fp_line
			(start 0.7874 0.4064)
			(end -0.7874 0.4064)
			(stroke
				(width 0.1524)
				(type default)
			)
			(layer "F.SilkS")
		)
		(fp_line
			(start 0.7874 -0.4064)
			(end 0.7874 0.4064)
			(stroke
				(width 0.1524)
				(type default)
			)
			(layer "F.SilkS")
		)
		(fp_line
			(start -0.7874 0.4064)
			(end -0.7874 -0.4064)
			(stroke
				(width 0.1524)
				(type default)
			)
			(layer "F.SilkS")
		)
		(fp_line
			(start -0.7874 -0.4064)
			(end 0.7874 -0.4064)
			(stroke
				(width 0.1524)
				(type default)
			)
			(layer "F.SilkS")
		)
		(fp_line
			(start 0.67945 0.3048)
			(end 0.120396 0.3048)
			(stroke
				(width 0.1)
				(type default)
			)
			(layer "F.Fab")
		)
		(fp_line
			(start 0.67945 -0.3048)
			(end 0.67945 0.3048)
			(stroke
				(width 0.1)
				(type default)
			)
			(layer "F.Fab")
		)
		(fp_line
			(start 0.12065 -0.2794)
			(end 0.12065 -0.3048)
			(stroke
				(width 0.1)
				(type default)
			)
			(layer "F.Fab")
		)
		(fp_line
			(start 0.12065 -0.3048)
			(end 0.67945 -0.3048)
			(stroke
				(width 0.1)
				(type default)
			)
			(layer "F.Fab")
		)
		(fp_line
			(start 0.120396 0.3048)
			(end 0.120396 0.2794)
			(stroke
				(width 0.1)
				(type default)
			)
			(layer "F.Fab")
		)
		(fp_line
			(start 0.120396 0.2794)
			(end -0.12065 0.2794)
			(stroke
				(width 0.1)
				(type default)
			)
			(layer "F.Fab")
		)
		(fp_line
			(start -0.12065 0.3048)
			(end -0.67945 0.3048)
			(stroke
				(width 0.1)
				(type default)
			)
			(layer "F.Fab")
		)
		(fp_line
			(start -0.12065 0.2794)
			(end -0.12065 0.3048)
			(stroke
				(width 0.1)
				(type default)
			)
			(layer "F.Fab")
		)
		(fp_line
			(start -0.12065 -0.2794)
			(end 0.12065 -0.2794)
			(stroke
				(width 0.1)
				(type default)
			)
			(layer "F.Fab")
		)
		(fp_line
			(start -0.12065 -0.305054)
			(end -0.12065 -0.2794)
			(stroke
				(width 0.1)
				(type default)
			)
			(layer "F.Fab")
		)
		(fp_line
			(start -0.67945 0.3048)
			(end -0.67945 -0.305054)
			(stroke
				(width 0.1)
				(type default)
			)
			(layer "F.Fab")
		)
		(fp_line
			(start -0.67945 -0.305054)
			(end -0.12065 -0.305054)
			(stroke
				(width 0.1)
				(type default)
			)
			(layer "F.Fab")
		)
		(pad "1" smd circle
			(at -0.40005 0 180)
			(size 0 0)
			(layers "F.Cu" "F.Mask" "F.Paste")
			(net "P3V3_AUX")
		)
		(pad "2" smd circle
			(at 0.40005 0 180)
			(size 0 0)
			(layers "F.Cu" "F.Mask" "F.Paste")
			(net "HP_LVC3_OCP_SFF_PRSNT2_PLD_N")
		)
	)
)
